FILE_TYPE = CONNECTIVITY;
{Allegro Design Entry HDL 17.2-2016 S081 (4005846) 1/11/2022}
"PAGE_NUMBER" = 85;
0"NC";
1"P3V3_AUX\g";
2"P3V3_AUX\g";
3"P12V_S3_AUX_CPU0_NVDIMM\g";
4"P12V_S3_AUX_CPU0_NVDIMM\g";
5"GND\g";
6"GND\g";
7"GND\g";
8"GND\g";
9"GND\g";
10"M_B_CPU0_SA_DQ<31:0>";
11"M_B_CPU0_SA_CB<7:0>";
12"M_B_CPU0_SA_CA<6:0>";
13"M_B_CPU0_SB_CA<6:0>";
14"M_B_CPU0_SB_CB<7:0>";
15"M_B_CPU0_SB_DQ<31:0>";
16"M_B_CPU0_SA_DQS_DP<9:0>";
17"M_B_CPU0_SB_DQS_DP<9:0>";
18"M_B_CPU0_SA_DQS_DN<9:0>";
19"M_B_CPU0_SB_DQS_DN<9:0>";
20"I3C_SPD_DDRABCD_CPU0_LVC1_SDA";
21"PD_CHB_CPU0_DIMM2_SAA";
22"M_B_CPU0_ALERT_N";
23"RST_M_AB_CPU0_FPGA_N";
24"M_B_CPU0_SB_CB<3>";
25"M_B_CPU0_SB_DQ<15>";
26"I3C_SPD_DDRABCD_CPU0_LVC1_SCL_R4";
27"I3C_SPD_DDRABCD_CPU0_LVC1_SCL";
28"PWRGD_CHB_CPU0_DIMM2";
29"TP_CHB_CPU0_DIMM2_FRU_6";
30"TP_CHB_CPU0_DIMM2_FRU_1";
31"TP_CHB_CPU0_DIMM2_FRU_2";
32"TP_CHB_CPU0_DIMM2_FRU_3";
33"TP_CHB_CPU0_DIMM2_FRU_4";
34"TP_CHB_CPU0_DIMM2_FRU_5";
35"M_B_CPU0_CLK_DP<1>";
36"M_B_CPU0_SB_DQS_DN<0>";
37"M_B_CPU0_SB_DQS_DN<1>";
38"M_B_CPU0_SB_DQS_DN<2>";
39"M_B_CPU0_SB_DQS_DN<4>";
40"M_B_CPU0_SB_DQS_DN<3>";
41"M_B_CPU0_SB_DQS_DN<5>";
42"M_B_CPU0_SB_DQS_DN<6>";
43"M_B_CPU0_SB_DQS_DN<7>";
44"M_B_CPU0_SB_DQS_DN<8>";
45"M_B_CPU0_SB_DQS_DN<9>";
46"M_B_CPU0_SA_DQS_DN<0>";
47"M_B_CPU0_SA_DQS_DN<1>";
48"M_B_CPU0_SA_DQS_DN<2>";
49"M_B_CPU0_SA_DQS_DN<3>";
50"M_B_CPU0_SA_DQS_DN<4>";
51"M_B_CPU0_SA_DQS_DN<5>";
52"M_B_CPU0_SA_DQS_DN<6>";
53"M_B_CPU0_SA_DQS_DN<7>";
54"M_B_CPU0_SA_DQS_DN<9>";
55"M_B_CPU0_SA_DQS_DN<8>";
56"M_B_CPU0_SB_DQS_DP<1>";
57"M_B_CPU0_SB_DQS_DP<0>";
58"M_B_CPU0_SB_DQS_DP<2>";
59"M_B_CPU0_SB_DQS_DP<3>";
60"M_B_CPU0_SB_DQS_DP<6>";
61"M_B_CPU0_SB_DQS_DP<4>";
62"M_B_CPU0_SB_DQS_DP<5>";
63"M_B_CPU0_SB_DQS_DP<7>";
64"M_B_CPU0_SB_DQS_DP<8>";
65"M_B_CPU0_SA_DQS_DP<0>";
66"M_B_CPU0_SB_DQS_DP<9>";
67"M_B_CPU0_SA_DQS_DP<1>";
68"M_B_CPU0_SA_DQS_DP<2>";
69"M_B_CPU0_SA_DQS_DP<3>";
70"M_B_CPU0_SA_DQS_DP<4>";
71"M_B_CPU0_SA_DQS_DP<5>";
72"M_B_CPU0_SA_DQS_DP<6>";
73"M_B_CPU0_SA_DQS_DP<7>";
74"M_B_CPU0_SA_DQS_DP<8>";
75"M_B_CPU0_SA_DQS_DP<9>";
76"M_B_CPU0_SA_DQ<12>";
77"M_B_CPU0_SB_CB<2>";
78"M_B_CPU0_SB_DQ<12>";
79"M_B_CPU0_SB_CB<0>";
80"M_B_CPU0_SA_DQ<19>";
81"M_B_CPU0_SA_DQ<18>";
82"M_B_CPU0_SB_CB<7>";
83"M_B_CPU0_SB_DQ<24>";
84"M_B_CPU0_SB_DQ<23>";
85"TP_CHB_CPU0_DIMM2_FRU_0";
86"M_B_CPU0_SB_PAR";
87"M_B_CPU0_SA_PAR";
88"M_B_CPU0_SB_RSP<1>";
89"M_B_CPU0_SA_RSP<1>";
90"M_B_CPU0_SB_DQ<0>";
91"M_B_CPU0_SB_DQ<1>";
92"M_B_CPU0_SB_DQ<2>";
93"M_B_CPU0_SB_DQ<3>";
94"M_B_CPU0_SB_DQ<4>";
95"M_B_CPU0_SB_DQ<5>";
96"M_B_CPU0_SB_DQ<6>";
97"M_B_CPU0_SB_DQ<7>";
98"M_B_CPU0_SB_DQ<8>";
99"M_B_CPU0_SB_DQ<9>";
100"M_B_CPU0_SB_DQ<10>";
101"M_B_CPU0_SB_DQ<11>";
102"M_B_CPU0_SB_DQ<13>";
103"M_B_CPU0_SB_DQ<14>";
104"M_B_CPU0_SB_DQ<16>";
105"M_B_CPU0_SB_DQ<17>";
106"M_B_CPU0_SB_DQ<18>";
107"M_B_CPU0_SB_DQ<19>";
108"M_B_CPU0_SB_DQ<20>";
109"M_B_CPU0_SB_DQ<21>";
110"M_B_CPU0_SB_DQ<22>";
111"M_B_CPU0_SB_DQ<25>";
112"M_B_CPU0_SB_DQ<26>";
113"M_B_CPU0_SB_DQ<27>";
114"M_B_CPU0_SB_DQ<28>";
115"M_B_CPU0_SB_DQ<29>";
116"M_B_CPU0_SB_DQ<30>";
117"M_B_CPU0_SB_DQ<31>";
118"M_B_CPU0_SA_DQ<0>";
119"M_B_CPU0_SA_DQ<1>";
120"M_B_CPU0_SA_DQ<2>";
121"M_B_CPU0_SA_DQ<3>";
122"M_B_CPU0_SA_DQ<4>";
123"M_B_CPU0_SA_DQ<5>";
124"M_B_CPU0_SA_DQ<6>";
125"M_B_CPU0_SA_DQ<7>";
126"M_B_CPU0_SA_DQ<8>";
127"M_B_CPU0_SA_DQ<9>";
128"M_B_CPU0_SA_DQ<10>";
129"M_B_CPU0_SA_DQ<11>";
130"M_B_CPU0_SA_DQ<13>";
131"M_B_CPU0_SA_DQ<14>";
132"M_B_CPU0_SA_DQ<15>";
133"M_B_CPU0_SA_DQ<16>";
134"M_B_CPU0_SA_DQ<17>";
135"M_B_CPU0_SA_DQ<20>";
136"M_B_CPU0_SA_DQ<21>";
137"M_B_CPU0_SA_DQ<22>";
138"M_B_CPU0_SA_DQ<23>";
139"M_B_CPU0_SA_DQ<24>";
140"M_B_CPU0_SA_DQ<25>";
141"M_B_CPU0_SA_DQ<26>";
142"M_B_CPU0_SA_DQ<27>";
143"M_B_CPU0_SA_DQ<28>";
144"M_B_CPU0_SA_DQ<29>";
145"M_B_CPU0_SA_DQ<30>";
146"M_B_CPU0_SB_CS_N<3>";
147"M_B_CPU0_SA_CS_N<3>";
148"M_B_CPU0_SB_CS_N<2>";
149"M_B_CPU0_SA_CS_N<2>";
150"M_B_CPU0_CLK_DN<1>";
151"M_B_CPU0_SB_CB<1>";
152"M_B_CPU0_SB_CB<4>";
153"M_B_CPU0_SB_CB<5>";
154"M_B_CPU0_SB_CB<6>";
155"M_B_CPU0_SA_CB<0>";
156"M_B_CPU0_SA_CB<2>";
157"M_B_CPU0_SA_CB<3>";
158"M_B_CPU0_SA_CB<5>";
159"M_B_CPU0_SA_CB<6>";
160"M_B_CPU0_SB_CA<6>";
161"M_B_CPU0_SA_CA<6>";
162"M_B_CPU0_SB_CA<5>";
163"M_B_CPU0_SA_CA<5>";
164"M_B_CPU0_SB_CA<4>";
165"M_B_CPU0_SA_CA<4>";
166"M_B_CPU0_SB_CA<3>";
167"M_B_CPU0_SA_CA<3>";
168"M_B_CPU0_SB_CA<2>";
169"M_B_CPU0_SA_CA<2>";
170"M_B_CPU0_SB_CA<1>";
171"M_B_CPU0_SA_CA<1>";
172"M_B_CPU0_SB_CA<0>";
173"M_B_CPU0_SA_CA<0>";
174"M_B_CPU0_SA_CB<1>";
175"M_B_CPU0_SA_CB<4>";
176"M_B_CPU0_SA_CB<7>";
177"M_B_CPU0_SA_DQ<31>";
178"PD_CHB_CPU0_DIMM2_SAA";
%"Q_RES"
"2","(-1950,250)","0","pure_quanta","I1";
;
PART_NUMBER"CS33572FB01"
VALUE"35.7K"
TOLERANCE"1%"
PACK_TYPE"0402LF"
WATTAGE"1/16W"
MATERIAL"CHIP"
$LOCATION"R29"
CDS_LIB"pure_quanta"
CDS_LOCATION"R29"
$SEC"1"
CDS_SEC"1";
"A"
$PN"1"178;
"B"
$PN"2"5;
%"TAP"
"1","(-525,3750)","0","standard","I100";
;
CDS_LIB"standard"
BODY_TYPE"PLUMBING"
HDL_TAP"TRUE";
"B \NAC \NWC"10;
"S \NAC"
BN"18"81;
%"TAP"
"1","(-525,3700)","0","standard","I101";
;
CDS_LIB"standard"
BODY_TYPE"PLUMBING"
HDL_TAP"TRUE";
"B \NAC \NWC"10;
"S \NAC"
BN"17"134;
%"TAP"
"1","(-525,3800)","0","standard","I102";
;
CDS_LIB"standard"
BODY_TYPE"PLUMBING"
HDL_TAP"TRUE";
"B \NAC \NWC"10;
"S \NAC"
BN"19"80;
%"TAP"
"1","(-525,3850)","0","standard","I103";
;
CDS_LIB"standard"
BODY_TYPE"PLUMBING"
HDL_TAP"TRUE";
"B \NAC \NWC"10;
"S \NAC"
BN"20"135;
%"TAP"
"1","(-525,3900)","0","standard","I104";
;
CDS_LIB"standard"
BODY_TYPE"PLUMBING"
HDL_TAP"TRUE";
"B \NAC \NWC"10;
"S \NAC"
BN"21"136;
%"TAP"
"1","(-525,3950)","0","standard","I105";
;
CDS_LIB"standard"
BODY_TYPE"PLUMBING"
HDL_TAP"TRUE";
"B \NAC \NWC"10;
"S \NAC"
BN"22"137;
%"TAP"
"1","(-525,4000)","0","standard","I106";
;
CDS_LIB"standard"
BODY_TYPE"PLUMBING"
HDL_TAP"TRUE";
"B \NAC \NWC"10;
"S \NAC"
BN"23"138;
%"TAP"
"1","(-525,4050)","0","standard","I107";
;
CDS_LIB"standard"
BODY_TYPE"PLUMBING"
HDL_TAP"TRUE";
"B \NAC \NWC"10;
"S \NAC"
BN"24"139;
%"TAP"
"1","(-525,4100)","0","standard","I108";
;
CDS_LIB"standard"
BODY_TYPE"PLUMBING"
HDL_TAP"TRUE";
"B \NAC \NWC"10;
"S \NAC"
BN"25"140;
%"TAP"
"1","(-525,4150)","0","standard","I109";
;
CDS_LIB"standard"
BODY_TYPE"PLUMBING"
HDL_TAP"TRUE";
"B \NAC \NWC"10;
"S \NAC"
BN"26"141;
%"VCC_CORE"
"1","(-3000,2275)","0","logical_power","I11";
;
HDL_POWER"P3V3_AUX"
CDS_LIB"logical_power";
"A"2;
%"TAP"
"1","(-525,4250)","0","standard","I110";
;
CDS_LIB"standard"
BODY_TYPE"PLUMBING"
HDL_TAP"TRUE";
"B \NAC \NWC"10;
"S \NAC"
BN"28"143;
%"TAP"
"1","(-525,4200)","0","standard","I111";
;
CDS_LIB"standard"
BODY_TYPE"PLUMBING"
HDL_TAP"TRUE";
"B \NAC \NWC"10;
"S \NAC"
BN"27"142;
%"TAP"
"1","(-2175,4300)","2","standard","I113";
;
CDS_LIB"standard"
BODY_TYPE"PLUMBING"
HDL_TAP"TRUE";
"B \NAC \NWC"12;
"S \NAC"
BN"4"165;
%"TAP"
"1","(-2175,4350)","2","standard","I114";
;
CDS_LIB"standard"
BODY_TYPE"PLUMBING"
HDL_TAP"TRUE";
"B \NAC \NWC"12;
"S \NAC"
BN"5"163;
%"TAP"
"1","(-2175,4400)","2","standard","I115";
;
CDS_LIB"standard"
BODY_TYPE"PLUMBING"
HDL_TAP"TRUE";
"B \NAC \NWC"12;
"S \NAC"
BN"6"161;
%"TAP"
"1","(-525,4350)","0","standard","I116";
;
CDS_LIB"standard"
BODY_TYPE"PLUMBING"
HDL_TAP"TRUE";
"B \NAC \NWC"10;
"S \NAC"
BN"30"145;
%"TAP"
"1","(-525,4300)","0","standard","I117";
;
CDS_LIB"standard"
BODY_TYPE"PLUMBING"
HDL_TAP"TRUE";
"B \NAC \NWC"10;
"S \NAC"
BN"29"144;
%"TAP"
"1","(-525,4400)","0","standard","I118";
;
CDS_LIB"standard"
BODY_TYPE"PLUMBING"
HDL_TAP"TRUE";
"B \NAC \NWC"10;
"S \NAC"
BN"31"177;
%"UNIVERSAL_GND"
"1","(1200,150)","0","logical_power","I119";
;
CDS_LIB"logical_power"
HDL_POWER"GND";
"A"9;
%"UNIVERSAL_GND"
"1","(2825,150)","0","logical_power","I120";
;
CDS_LIB"logical_power"
HDL_POWER"GND";
"A"8;
%"Q_CAP"
"1","(1200,525)","0","pure_quanta","I121";
;
PART_NUMBER"CH5221MEB00"
TOLERANCE"20%"
VALUE"2.2UF"
PACK_TYPE"C0402"
MATERIAL"X6S"
VOLTAGE"6.3V"
$LOCATION"C11"
CDS_LIB"pure_quanta"
CDS_LOCATION"C11"
$SEC"1"
CDS_SEC"1";
"B"
$PN"2"9;
"A"
$PN"1"1;
%"VCC_CORE"
"1","(1200,850)","0","logical_power","I122";
;
HDL_POWER"P3V3_AUX"
CDS_LIB"logical_power";
"A"1;
%"Q_CAP"
"1","(2200,525)","0","pure_quanta","I125";
;
PART_NUMBER"CH6103KEA00"
PACK_TYPE"C0805"
VALUE"10UF"
MATERIAL"X6S"
VOLTAGE"16V"
TOLERANCE"10%"
$LOCATION"C12"
CDS_LIB"pure_quanta"
CDS_LOCATION"C12"
$SEC"1"
CDS_SEC"1";
"B"
$PN"2"8;
"A"
$PN"1"4;
%"VCC_CORE"
"1","(2200,850)","0","logical_power","I126";
;
HDL_POWER"P12V_S3_AUX_CPU0_NVDIMM"
CDS_LIB"logical_power";
"A"4;
%"Q_CAP"
"1","(2825,525)","0","pure_quanta","I127";
;
PART_NUMBER"CH6103KEA00"
TOLERANCE"10%"
VALUE"10UF"
PACK_TYPE"C0805"
VOLTAGE"16V"
MATERIAL"X6S"
$LOCATION"C13"
CDS_LIB"pure_quanta"
CDS_LOCATION"C13"
$SEC"1"
CDS_SEC"1";
"B"
$PN"2"8;
"A"
$PN"1"4;
%"TAP"
"1","(2225,2450)","0","standard","I128";
;
CDS_LIB"standard"
BODY_TYPE"PLUMBING"
HDL_TAP"TRUE";
"B \NAC \NWC"17;
"S \NAC"
BN"0"57;
%"TAP"
"1","(2400,2500)","0","standard","I129";
;
CDS_LIB"standard"
BODY_TYPE"PLUMBING"
HDL_TAP"TRUE";
"B \NAC \NWC"19;
"S \NAC"
BN"1"37;
%"TAP"
"1","(2400,2400)","0","standard","I130";
;
CDS_LIB"standard"
BODY_TYPE"PLUMBING"
HDL_TAP"TRUE";
"B \NAC \NWC"19;
"S \NAC"
BN"0"36;
%"TAP"
"1","(2225,2550)","0","standard","I131";
;
CDS_LIB"standard"
BODY_TYPE"PLUMBING"
HDL_TAP"TRUE";
"B \NAC \NWC"17;
"S \NAC"
BN"1"56;
%"TAP"
"1","(2225,2650)","0","standard","I132";
;
CDS_LIB"standard"
BODY_TYPE"PLUMBING"
HDL_TAP"TRUE";
"B \NAC \NWC"17;
"S \NAC"
BN"2"58;
%"TAP"
"1","(2225,2750)","0","standard","I133";
;
CDS_LIB"standard"
BODY_TYPE"PLUMBING"
HDL_TAP"TRUE";
"B \NAC \NWC"17;
"S \NAC"
BN"3"59;
%"TAP"
"1","(2400,2600)","0","standard","I134";
;
CDS_LIB"standard"
BODY_TYPE"PLUMBING"
HDL_TAP"TRUE";
"B \NAC \NWC"19;
"S \NAC"
BN"2"38;
%"TAP"
"1","(2400,2700)","0","standard","I135";
;
CDS_LIB"standard"
BODY_TYPE"PLUMBING"
HDL_TAP"TRUE";
"B \NAC \NWC"19;
"S \NAC"
BN"3"40;
%"TAP"
"1","(2225,2850)","0","standard","I136";
;
CDS_LIB"standard"
BODY_TYPE"PLUMBING"
HDL_TAP"TRUE";
"B \NAC \NWC"17;
"S \NAC"
BN"4"61;
%"TAP"
"1","(2225,2950)","0","standard","I137";
;
CDS_LIB"standard"
BODY_TYPE"PLUMBING"
HDL_TAP"TRUE";
"B \NAC \NWC"17;
"S \NAC"
BN"5"62;
%"TAP"
"1","(2400,2800)","0","standard","I138";
;
CDS_LIB"standard"
BODY_TYPE"PLUMBING"
HDL_TAP"TRUE";
"B \NAC \NWC"19;
"S \NAC"
BN"4"39;
%"TAP"
"1","(2400,3000)","0","standard","I139";
;
CDS_LIB"standard"
BODY_TYPE"PLUMBING"
HDL_TAP"TRUE";
"B \NAC \NWC"19;
"S \NAC"
BN"6"42;
%"TAP"
"1","(2400,2900)","0","standard","I140";
;
CDS_LIB"standard"
BODY_TYPE"PLUMBING"
HDL_TAP"TRUE";
"B \NAC \NWC"19;
"S \NAC"
BN"5"41;
%"TAP"
"1","(2225,3050)","0","standard","I141";
;
CDS_LIB"standard"
BODY_TYPE"PLUMBING"
HDL_TAP"TRUE";
"B \NAC \NWC"17;
"S \NAC"
BN"6"60;
%"TAP"
"1","(2225,3150)","0","standard","I142";
;
CDS_LIB"standard"
BODY_TYPE"PLUMBING"
HDL_TAP"TRUE";
"B \NAC \NWC"17;
"S \NAC"
BN"7"63;
%"TAP"
"1","(2225,3250)","0","standard","I143";
;
CDS_LIB"standard"
BODY_TYPE"PLUMBING"
HDL_TAP"TRUE";
"B \NAC \NWC"17;
"S \NAC"
BN"8"64;
%"TAP"
"1","(2400,3100)","0","standard","I144";
;
CDS_LIB"standard"
BODY_TYPE"PLUMBING"
HDL_TAP"TRUE";
"B \NAC \NWC"19;
"S \NAC"
BN"7"43;
%"TAP"
"1","(2400,3200)","0","standard","I145";
;
CDS_LIB"standard"
BODY_TYPE"PLUMBING"
HDL_TAP"TRUE";
"B \NAC \NWC"19;
"S \NAC"
BN"8"44;
%"TAP"
"1","(2225,3350)","0","standard","I146";
;
CDS_LIB"standard"
BODY_TYPE"PLUMBING"
HDL_TAP"TRUE";
"B \NAC \NWC"17;
"S \NAC"
BN"9"66;
%"TAP"
"1","(2225,3500)","0","standard","I147";
;
CDS_LIB"standard"
BODY_TYPE"PLUMBING"
HDL_TAP"TRUE";
"B \NAC \NWC"16;
"S \NAC"
BN"0"65;
%"TAP"
"1","(2400,3450)","0","standard","I148";
;
CDS_LIB"standard"
BODY_TYPE"PLUMBING"
HDL_TAP"TRUE";
"B \NAC \NWC"18;
"S \NAC"
BN"0"46;
%"TAP"
"1","(2400,3300)","0","standard","I149";
;
CDS_LIB"standard"
BODY_TYPE"PLUMBING"
HDL_TAP"TRUE";
"B \NAC \NWC"19;
"S \NAC"
BN"9"45;
%"TAP"
"1","(2225,3600)","0","standard","I150";
;
CDS_LIB"standard"
BODY_TYPE"PLUMBING"
HDL_TAP"TRUE";
"B \NAC \NWC"16;
"S \NAC"
BN"1"67;
%"TAP"
"1","(2225,3700)","0","standard","I151";
;
CDS_LIB"standard"
BODY_TYPE"PLUMBING"
HDL_TAP"TRUE";
"B \NAC \NWC"16;
"S \NAC"
BN"2"68;
%"TAP"
"1","(2400,3550)","0","standard","I152";
;
CDS_LIB"standard"
BODY_TYPE"PLUMBING"
HDL_TAP"TRUE";
"B \NAC \NWC"18;
"S \NAC"
BN"1"47;
%"TAP"
"1","(2400,3650)","0","standard","I153";
;
CDS_LIB"standard"
BODY_TYPE"PLUMBING"
HDL_TAP"TRUE";
"B \NAC \NWC"18;
"S \NAC"
BN"2"48;
%"TAP"
"1","(2400,3750)","0","standard","I154";
;
CDS_LIB"standard"
BODY_TYPE"PLUMBING"
HDL_TAP"TRUE";
"B \NAC \NWC"18;
"S \NAC"
BN"3"49;
%"TAP"
"1","(2225,3900)","0","standard","I155";
;
CDS_LIB"standard"
BODY_TYPE"PLUMBING"
HDL_TAP"TRUE";
"B \NAC \NWC"16;
"S \NAC"
BN"4"70;
%"TAP"
"1","(2225,3800)","0","standard","I156";
;
CDS_LIB"standard"
BODY_TYPE"PLUMBING"
HDL_TAP"TRUE";
"B \NAC \NWC"16;
"S \NAC"
BN"3"69;
%"TAP"
"1","(2225,4000)","0","standard","I157";
;
CDS_LIB"standard"
BODY_TYPE"PLUMBING"
HDL_TAP"TRUE";
"B \NAC \NWC"16;
"S \NAC"
BN"5"71;
%"TAP"
"1","(2400,3850)","0","standard","I158";
;
CDS_LIB"standard"
BODY_TYPE"PLUMBING"
HDL_TAP"TRUE";
"B \NAC \NWC"18;
"S \NAC"
BN"4"50;
%"TAP"
"1","(2400,3950)","0","standard","I159";
;
CDS_LIB"standard"
BODY_TYPE"PLUMBING"
HDL_TAP"TRUE";
"B \NAC \NWC"18;
"S \NAC"
BN"5"51;
%"TAP"
"1","(2225,4100)","0","standard","I160";
;
CDS_LIB"standard"
BODY_TYPE"PLUMBING"
HDL_TAP"TRUE";
"B \NAC \NWC"16;
"S \NAC"
BN"6"72;
%"TAP"
"1","(2225,4200)","0","standard","I161";
;
CDS_LIB"standard"
BODY_TYPE"PLUMBING"
HDL_TAP"TRUE";
"B \NAC \NWC"16;
"S \NAC"
BN"7"73;
%"TAP"
"1","(2400,4050)","0","standard","I162";
;
CDS_LIB"standard"
BODY_TYPE"PLUMBING"
HDL_TAP"TRUE";
"B \NAC \NWC"18;
"S \NAC"
BN"6"52;
%"TAP"
"1","(2400,4150)","0","standard","I163";
;
CDS_LIB"standard"
BODY_TYPE"PLUMBING"
HDL_TAP"TRUE";
"B \NAC \NWC"18;
"S \NAC"
BN"7"53;
%"TAP"
"1","(2400,4250)","0","standard","I164";
;
CDS_LIB"standard"
BODY_TYPE"PLUMBING"
HDL_TAP"TRUE";
"B \NAC \NWC"18;
"S \NAC"
BN"8"55;
%"TAP"
"1","(2225,4400)","0","standard","I168";
;
CDS_LIB"standard"
BODY_TYPE"PLUMBING"
HDL_TAP"TRUE";
"B \NAC \NWC"16;
"S \NAC"
BN"9"75;
%"TAP"
"1","(2225,4300)","0","standard","I169";
;
CDS_LIB"standard"
BODY_TYPE"PLUMBING"
HDL_TAP"TRUE";
"B \NAC \NWC"16;
"S \NAC"
BN"8"74;
%"TAP"
"1","(2400,4350)","0","standard","I170";
;
CDS_LIB"standard"
BODY_TYPE"PLUMBING"
HDL_TAP"TRUE";
"B \NAC \NWC"18;
"S \NAC"
BN"9"54;
%"UNIVERSAL_GND"
"1","(3900,700)","0","logical_power","I173";
;
CDS_LIB"logical_power"
HDL_POWER"GND";
"A"7;
%"SCONN288_ADR50017P087CC"
"3","(4750,2775)","0","pure_quanta","I174";
;
PART_NUMBER"DFHST8FS460"
MATERIAL"IO"
PART_TYPE"SMLF"
VALUE"SCONN288_ADR50017-P087CC"
$LOCATION"J4"
CDS_LIB"pure_quanta"
CDS_LMAN_SYM_OUTLINE"-450,1775,450,-1775"
NEEDS_NO_SIZE"TRUE"
CDS_LOCATION"J4"
$SEC"3"
CDS_SEC"3";
"G3"
$PN"G3"6;
"G2"
$PN"G2"6;
"G1"
$PN"G1"6;
"VSS62"
$PN"141"6;
"VSS61"
$PN"139"6;
"VSS60"
$PN"136"6;
"VSS58"
$PN"132"6;
"VSS104"
$PN"240"7;
"VSS102"
$PN"235"7;
"VSS100"
$PN"230"7;
"VIN_BULK2"
$PN"146"3;
"VIN_BULK1"
$PN"145"3;
"VIN_BULK0"
$PN"1"3;
"VSS126"
$PN"288"7;
"VSS125"
$PN"286"7;
"VSS124"
$PN"284"7;
"VSS123"
$PN"281"7;
"VSS122"
$PN"279"7;
"VSS121"
$PN"277"7;
"VSS120"
$PN"275"7;
"VSS119"
$PN"273"7;
"VSS118"
$PN"270"7;
"VSS117"
$PN"268"7;
"VSS116"
$PN"266"7;
"VSS115"
$PN"264"7;
"VSS114"
$PN"262"7;
"VSS113"
$PN"259"7;
"VSS112"
$PN"257"7;
"VSS111"
$PN"255"7;
"VSS110"
$PN"253"7;
"VSS109"
$PN"251"7;
"VSS108"
$PN"248"7;
"VSS107"
$PN"246"7;
"VSS106"
$PN"244"7;
"VSS105"
$PN"242"7;
"VSS103"
$PN"237"7;
"VSS101"
$PN"233"7;
"VSS99"
$PN"228"7;
"VSS98"
$PN"226"7;
"VSS97"
$PN"224"7;
"VSS96"
$PN"222"7;
"VSS95"
$PN"219"7;
"VSS94"
$PN"216"7;
"VSS93"
$PN"214"7;
"VSS92"
$PN"212"7;
"VSS91"
$PN"210"7;
"VSS90"
$PN"208"7;
"VSS89"
$PN"206"7;
"VSS88"
$PN"204"7;
"VSS87"
$PN"202"7;
"VSS86"
$PN"199"7;
"VSS85"
$PN"197"7;
"VSS84"
$PN"195"7;
"VSS83"
$PN"193"7;
"VSS82"
$PN"191"7;
"VSS81"
$PN"188"7;
"VSS80"
$PN"186"7;
"VSS79"
$PN"184"7;
"VSS78"
$PN"182"7;
"VSS77"
$PN"180"7;
"VSS76"
$PN"177"7;
"VSS75"
$PN"175"7;
"VSS74"
$PN"173"7;
"VSS73"
$PN"171"7;
"VSS72"
$PN"169"7;
"VSS71"
$PN"166"7;
"VSS70"
$PN"164"7;
"VSS69"
$PN"162"7;
"VSS68"
$PN"160"7;
"VSS67"
$PN"158"7;
"VSS66"
$PN"155"7;
"VSS65"
$PN"153"7;
"VSS64"
$PN"151"7;
"VSS63"
$PN"143"6;
"VSS59"
$PN"134"6;
"VSS57"
$PN"130"6;
"VSS56"
$PN"128"6;
"VSS55"
$PN"125"6;
"VSS54"
$PN"123"6;
"VSS53"
$PN"121"6;
"VSS52"
$PN"119"6;
"VSS51"
$PN"117"6;
"VSS50"
$PN"114"6;
"VSS49"
$PN"112"6;
"VSS48"
$PN"110"6;
"VSS47"
$PN"108"6;
"VSS46"
$PN"106"6;
"VSS45"
$PN"103"6;
"VSS44"
$PN"101"6;
"VSS43"
$PN"99"6;
"VSS42"
$PN"97"6;
"VSS41"
$PN"95"6;
"VSS40"
$PN"92"6;
"VSS39"
$PN"90"6;
"VSS38"
$PN"88"6;
"VSS37"
$PN"85"6;
"VSS36"
$PN"83"6;
"VSS35"
$PN"81"6;
"VSS34"
$PN"79"6;
"VSS33"
$PN"77"6;
"VSS32"
$PN"75"6;
"VSS31"
$PN"73"6;
"VSS30"
$PN"71"6;
"VSS29"
$PN"69"6;
"VSS28"
$PN"67"6;
"VSS27"
$PN"65"6;
"VSS26"
$PN"63"6;
"VSS25"
$PN"61"6;
"VSS24"
$PN"59"6;
"VSS23"
$PN"57"6;
"VSS22"
$PN"54"6;
"VSS21"
$PN"52"6;
"VSS20"
$PN"50"6;
"VSS19"
$PN"48"6;
"VSS18"
$PN"46"6;
"VSS17"
$PN"43"6;
"VSS16"
$PN"41"6;
"VSS15"
$PN"39"6;
"VSS14"
$PN"37"6;
"VSS13"
$PN"35"6;
"VSS12"
$PN"32"6;
"VSS11"
$PN"30"6;
"VSS10"
$PN"28"6;
"VSS9"
$PN"26"6;
"VSS8"
$PN"24"6;
"VSS7"
$PN"21"6;
"VSS6"
$PN"19"6;
"VSS5"
$PN"17"6;
"VSS4"
$PN"15"6;
"VSS3"
$PN"13"6;
"VSS2"
$PN"10"6;
"VSS1"
$PN"8"6;
"VSS0"
$PN"6"6;
%"UNIVERSAL_GND"
"1","(5600,700)","0","logical_power","I175";
;
CDS_LIB"logical_power"
HDL_POWER"GND";
"A"6;
%"VCC_CORE"
"1","(3900,4950)","0","logical_power","I176";
;
HDL_POWER"P12V_S3_AUX_CPU0_NVDIMM"
CDS_LIB"logical_power";
"A"3;
%"SCONN288_ADR50017P087CC"
"2","(1325,3400)","0","pure_quanta","I178";
;
PART_NUMBER"DFHST8FS460"
PART_TYPE"SMLF"
VALUE"SCONN288_ADR50017-P087CC"
MATERIAL"IO"
LOCATION"J4"
NEEDS_NO_SIZE"TRUE"
CDS_LMAN_SYM_OUTLINE"-600,1150,600,-1150"
CDS_LIB"pure_quanta"
$SEC"2"
CDS_SEC"2";
"DQS7_A_C||TDQS7_A_C \B"
$PN"178"53;
"DQS6_A_T||TDQS6_A_T"
$PN"168"72;
"DQS8_B_T||TDQS8_B_T"
$PN"283"64;
"DQS8_B_C||TDQS8_B_C \B"
$PN"282"44;
"DQS7_B_T||TDQS7_B_T"
$PN"272"63;
"DQS0_A_C \B"
$PN"12"46;
"DQS0_A_T"
$PN"11"65;
"DQS0_B_C \B"
$PN"105"36;
"DQS0_B_T"
$PN"104"57;
"DQS1_A_C \B"
$PN"23"47;
"DQS1_A_T"
$PN"22"67;
"DQS1_B_C \B"
$PN"116"37;
"DQS1_B_T"
$PN"115"56;
"DQS2_A_C \B"
$PN"34"48;
"DQS2_A_T"
$PN"33"68;
"DQS2_B_C \B"
$PN"127"38;
"DQS2_B_T"
$PN"126"58;
"DQS3_A_C \B"
$PN"45"49;
"DQS3_A_T"
$PN"44"69;
"DQS3_B_C \B"
$PN"138"40;
"DQS3_B_T"
$PN"137"59;
"DQS4_A_C \B"
$PN"56"50;
"DQS4_A_T"
$PN"55"70;
"DQS4_B_C \B"
$PN"238"39;
"DQS4_B_T"
$PN"239"61;
"DQS5_A_C||TDQS5_A_C||DQS5_A_T||TDQS5_A_T \B"
$PN"156"51;
"DQS5_A_T||TDQS5_A_T"
$PN"157"71;
"DQS5_B_C||TDQS5_B_C \B"
$PN"249"41;
"DQS5_B_T||TDQS5_B_T"
$PN"250"62;
"DQS6_A_C||TDQS6_A_C||DQS6_A_T||TDQS6_A_T \B"
$PN"167"52;
"DQS6_B_C||TDQS6_B_C \B"
$PN"260"42;
"DQS6_B_T||TDQS6_B_T"
$PN"261"60;
"DQS7_A_T||TDQS7_A_T"
$PN"179"73;
"DQS7_B_C||TDQS7_B_C \B"
$PN"271"43;
"DQS8_A_C||TDQS8_A_C \B"
$PN"189"55;
"DQS8_A_T||TDQS8_A_T"
$PN"190"74;
"DQS9_A_C||TDQS9_A_C \B"
$PN"200"54;
"DQS9_A_T||TDQS9_A_T"
$PN"201"75;
"DQS9_B_C||TDQS9_B_C \B"
$PN"94"45;
"DQS9_B_T||TDQS9_B_T||DBI4_B_N"
$PN"93"66;
%"Q_RES"
"1","(-3275,1700)","0","pure_quanta","I180";
;
PART_NUMBER"CS04992FB07"
VALUE"49.9"
MATERIAL"CHIP"
$LOCATION"R3878"
CDS_LIB"pure_quanta"
PACK_TYPE"0402LF"
TOLERANCE"1%"
WATTAGE"1/16W"
CDS_LOCATION"R3878"
$SEC"1"
CDS_SEC"1";
"B"
$PN"2"27;
"A"
$PN"1"26;
%"UNIVERSAL_GND"
"1","(-1950,25)","0","logical_power","I2";
;
CDS_LIB"logical_power"
HDL_POWER"GND";
"A"5;
%"SCONN288_ADR50017P087CC"
"1","(-1350,2675)","0","pure_quanta","I23";
;
PART_NUMBER"DFHST8FS460"
MATERIAL"IO"
PART_TYPE"SMLF"
VALUE"SCONN288_ADR50017-P087CC"
$LOCATION"J4"
NEEDS_NO_SIZE"TRUE"
CDS_LMAN_SYM_OUTLINE"-450,1875,450,-1875"
CDS_LIB"pure_quanta"
CDS_LOCATION"J4"
$SEC"1"
CDS_SEC"1";
"DQ31_A"
$PN"194"177;
"CB7_A"
$PN"205"176;
"CB4_A"
$PN"58"175;
"CB1_A"
$PN"53"174;
"CB7_B"
$PN"236"82;
"ALERT_N \B"
$PN"62"22;
"CA0_A"
$PN"66"173;
"CA0_B"
$PN"76"172;
"CA1_A"
$PN"211"171;
"CA1_B"
$PN"221"170;
"CA2_A"
$PN"68"169;
"CA2_B"
$PN"78"168;
"CA3_A"
$PN"213"167;
"CA3_B"
$PN"223"166;
"CA4_A"
$PN"70"165;
"CA4_B"
$PN"80"164;
"CA5_A"
$PN"215"163;
"CA5_B"
$PN"225"162;
"CA6_A"
$PN"72"161;
"CA6_B"
$PN"82"160;
"CB6_A"
$PN"203"159;
"CB5_A"
$PN"60"158;
"CB3_A"
$PN"198"157;
"CB2_A"
$PN"196"156;
"CB0_A"
$PN"51"155;
"CB6_B"
$PN"234"154;
"CB5_B"
$PN"91"153;
"CB4_B"
$PN"89"152;
"CB3_B"
$PN"243"24;
"CB2_B"
$PN"241"77;
"CB1_B"
$PN"98"151;
"CB0_B"
$PN"96"79;
"CK_C \B"
$PN"218"150;
"CK_T"
$PN"217"35;
"CS0_A_N"
$PN"64"149;
"CS0_B_N"
$PN"84"148;
"CS1_A_N"
$PN"209"147;
"CS1_B_N"
$PN"229"146;
"DQ30_A"
$PN"192"145;
"DQ29_A"
$PN"49"144;
"DQ28_A"
$PN"47"143;
"DQ27_A"
$PN"187"142;
"DQ26_A"
$PN"185"141;
"DQ25_A"
$PN"42"140;
"DQ24_A"
$PN"40"139;
"DQ23_A"
$PN"183"138;
"DQ22_A"
$PN"181"137;
"DQ21_A"
$PN"38"136;
"DQ20_A"
$PN"36"135;
"DQ19_A"
$PN"176"80;
"DQ18_A"
$PN"174"81;
"DQ17_A"
$PN"31"134;
"DQ16_A"
$PN"29"133;
"DQ15_A"
$PN"172"132;
"DQ14_A"
$PN"170"131;
"DQ13_A"
$PN"27"130;
"DQ12_A"
$PN"25"76;
"DQ11_A"
$PN"165"129;
"DQ10_A"
$PN"163"128;
"DQ9_A"
$PN"20"127;
"DQ8_A"
$PN"18"126;
"DQ7_A"
$PN"161"125;
"DQ6_A"
$PN"159"124;
"DQ5_A"
$PN"16"123;
"DQ4_A"
$PN"14"122;
"DQ3_A"
$PN"154"121;
"DQ2_A"
$PN"152"120;
"DQ1_A"
$PN"9"119;
"DQ0_A"
$PN"7"118;
"DQ31_B"
$PN"287"117;
"DQ30_B"
$PN"285"116;
"DQ29_B"
$PN"142"115;
"DQ28_B"
$PN"140"114;
"DQ27_B"
$PN"280"113;
"DQ26_B"
$PN"278"112;
"DQ25_B"
$PN"135"111;
"DQ24_B"
$PN"133"83;
"DQ23_B"
$PN"276"84;
"DQ22_B"
$PN"274"110;
"DQ21_B"
$PN"131"109;
"DQ20_B"
$PN"129"108;
"DQ19_B"
$PN"269"107;
"DQ18_B"
$PN"267"106;
"DQ17_B"
$PN"124"105;
"DQ16_B"
$PN"122"104;
"DQ15_B"
$PN"265"25;
"DQ14_B"
$PN"263"103;
"DQ13_B"
$PN"120"102;
"DQ12_B"
$PN"118"78;
"DQ11_B"
$PN"258"101;
"DQ10_B"
$PN"256"100;
"DQ9_B"
$PN"113"99;
"DQ8_B"
$PN"111"98;
"DQ7_B"
$PN"254"97;
"DQ6_B"
$PN"252"96;
"DQ5_B"
$PN"109"95;
"DQ4_B"
$PN"107"94;
"DQ3_B"
$PN"247"93;
"DQ2_B"
$PN"245"92;
"DQ1_B"
$PN"102"91;
"DQ0_B"
$PN"100"90;
"HSA"
$PN"148"21;
"HSCL"
$PN"4"26;
"HSDA"
$PN"5"20;
"LBD||RSP_A_N"
$PN"86"89;
"LBS||RSP_B_N"
$PN"87"88;
"PAR_A"
$PN"74"87;
"PAR_B"
$PN"227"86;
"PWR_GOOD||FAIL_N"
$PN"147"28;
"RESET_N \B"
$PN"207"23;
"RFU6"
$PN"232"29;
"RFU5"
$PN"231"34;
"RFU4"
$PN"220"33;
"RFU3"
$PN"150"32;
"RFU2"
$PN"149"31;
"RFU1"
$PN"144"30;
"RFU0"
$PN"2"85;
"VIN_MGMT"
$PN"3"2;
%"TAP"
"1","(-2175,2200)","2","standard","I24";
;
CDS_LIB"standard"
BODY_TYPE"PLUMBING"
HDL_TAP"TRUE";
"B \NAC \NWC"14;
"S \NAC"
BN"0"79;
%"TAP"
"1","(-525,1200)","0","standard","I25";
;
CDS_LIB"standard"
BODY_TYPE"PLUMBING"
HDL_TAP"TRUE";
"B \NAC \NWC"15;
"S \NAC"
BN"0"90;
%"TAP"
"1","(-525,1250)","0","standard","I26";
;
CDS_LIB"standard"
BODY_TYPE"PLUMBING"
HDL_TAP"TRUE";
"B \NAC \NWC"15;
"S \NAC"
BN"1"91;
%"TAP"
"1","(-525,1300)","0","standard","I27";
;
CDS_LIB"standard"
BODY_TYPE"PLUMBING"
HDL_TAP"TRUE";
"B \NAC \NWC"15;
"S \NAC"
BN"2"92;
%"TAP"
"1","(-525,1350)","0","standard","I28";
;
CDS_LIB"standard"
BODY_TYPE"PLUMBING"
HDL_TAP"TRUE";
"B \NAC \NWC"15;
"S \NAC"
BN"3"93;
%"TAP"
"1","(-525,1450)","0","standard","I29";
;
CDS_LIB"standard"
BODY_TYPE"PLUMBING"
HDL_TAP"TRUE";
"B \NAC \NWC"15;
"S \NAC"
BN"5"95;
%"TAP"
"1","(-525,1400)","0","standard","I30";
;
CDS_LIB"standard"
BODY_TYPE"PLUMBING"
HDL_TAP"TRUE";
"B \NAC \NWC"15;
"S \NAC"
BN"4"94;
%"TAP"
"1","(-525,1500)","0","standard","I31";
;
CDS_LIB"standard"
BODY_TYPE"PLUMBING"
HDL_TAP"TRUE";
"B \NAC \NWC"15;
"S \NAC"
BN"6"96;
%"TAP"
"1","(-525,1600)","0","standard","I32";
;
CDS_LIB"standard"
BODY_TYPE"PLUMBING"
HDL_TAP"TRUE";
"B \NAC \NWC"15;
"S \NAC"
BN"8"98;
%"TAP"
"1","(-525,1550)","0","standard","I33";
;
CDS_LIB"standard"
BODY_TYPE"PLUMBING"
HDL_TAP"TRUE";
"B \NAC \NWC"15;
"S \NAC"
BN"7"97;
%"TAP"
"1","(-525,1700)","0","standard","I34";
;
CDS_LIB"standard"
BODY_TYPE"PLUMBING"
HDL_TAP"TRUE";
"B \NAC \NWC"15;
"S \NAC"
BN"10"100;
%"TAP"
"1","(-525,1650)","0","standard","I35";
;
CDS_LIB"standard"
BODY_TYPE"PLUMBING"
HDL_TAP"TRUE";
"B \NAC \NWC"15;
"S \NAC"
BN"9"99;
%"TAP"
"1","(-525,1750)","0","standard","I36";
;
CDS_LIB"standard"
BODY_TYPE"PLUMBING"
HDL_TAP"TRUE";
"B \NAC \NWC"15;
"S \NAC"
BN"11"101;
%"TAP"
"1","(-525,1800)","0","standard","I37";
;
CDS_LIB"standard"
BODY_TYPE"PLUMBING"
HDL_TAP"TRUE";
"B \NAC \NWC"15;
"S \NAC"
BN"12"78;
%"TAP"
"1","(-525,1850)","0","standard","I38";
;
CDS_LIB"standard"
BODY_TYPE"PLUMBING"
HDL_TAP"TRUE";
"B \NAC \NWC"15;
"S \NAC"
BN"13"102;
%"TAP"
"1","(-525,1900)","0","standard","I39";
;
CDS_LIB"standard"
BODY_TYPE"PLUMBING"
HDL_TAP"TRUE";
"B \NAC \NWC"15;
"S \NAC"
BN"14"103;
%"TAP"
"1","(-525,1950)","0","standard","I40";
;
CDS_LIB"standard"
BODY_TYPE"PLUMBING"
HDL_TAP"TRUE";
"B \NAC \NWC"15;
"S \NAC"
BN"15"25;
%"TAP"
"1","(-525,2000)","0","standard","I41";
;
CDS_LIB"standard"
BODY_TYPE"PLUMBING"
HDL_TAP"TRUE";
"B \NAC \NWC"15;
"S \NAC"
BN"16"104;
%"TAP"
"1","(-525,2050)","0","standard","I42";
;
CDS_LIB"standard"
BODY_TYPE"PLUMBING"
HDL_TAP"TRUE";
"B \NAC \NWC"15;
"S \NAC"
BN"17"105;
%"TAP"
"1","(-525,2100)","0","standard","I43";
;
CDS_LIB"standard"
BODY_TYPE"PLUMBING"
HDL_TAP"TRUE";
"B \NAC \NWC"15;
"S \NAC"
BN"18"106;
%"TAP"
"1","(-525,2200)","0","standard","I44";
;
CDS_LIB"standard"
BODY_TYPE"PLUMBING"
HDL_TAP"TRUE";
"B \NAC \NWC"15;
"S \NAC"
BN"20"108;
%"TAP"
"1","(-525,2150)","0","standard","I45";
;
CDS_LIB"standard"
BODY_TYPE"PLUMBING"
HDL_TAP"TRUE";
"B \NAC \NWC"15;
"S \NAC"
BN"19"107;
%"TAP"
"1","(-2175,2350)","2","standard","I46";
;
CDS_LIB"standard"
BODY_TYPE"PLUMBING"
HDL_TAP"TRUE";
"B \NAC \NWC"14;
"S \NAC"
BN"3"24;
%"TAP"
"1","(-2175,2300)","2","standard","I47";
;
CDS_LIB"standard"
BODY_TYPE"PLUMBING"
HDL_TAP"TRUE";
"B \NAC \NWC"14;
"S \NAC"
BN"2"77;
%"TAP"
"1","(-2175,2250)","2","standard","I48";
;
CDS_LIB"standard"
BODY_TYPE"PLUMBING"
HDL_TAP"TRUE";
"B \NAC \NWC"14;
"S \NAC"
BN"1"151;
%"TAP"
"1","(-2175,2450)","2","standard","I49";
;
CDS_LIB"standard"
BODY_TYPE"PLUMBING"
HDL_TAP"TRUE";
"B \NAC \NWC"14;
"S \NAC"
BN"5"153;
%"TAP"
"1","(-2175,2400)","2","standard","I50";
;
CDS_LIB"standard"
BODY_TYPE"PLUMBING"
HDL_TAP"TRUE";
"B \NAC \NWC"14;
"S \NAC"
BN"4"152;
%"TAP"
"1","(-2175,2500)","2","standard","I51";
;
CDS_LIB"standard"
BODY_TYPE"PLUMBING"
HDL_TAP"TRUE";
"B \NAC \NWC"14;
"S \NAC"
BN"6"154;
%"TAP"
"1","(-2175,2550)","2","standard","I52";
;
CDS_LIB"standard"
BODY_TYPE"PLUMBING"
HDL_TAP"TRUE";
"B \NAC \NWC"14;
"S \NAC"
BN"7"82;
%"TAP"
"1","(-2175,2700)","2","standard","I53";
;
CDS_LIB"standard"
BODY_TYPE"PLUMBING"
HDL_TAP"TRUE";
"B \NAC \NWC"11;
"S \NAC"
BN"1"174;
%"TAP"
"1","(-2175,2650)","2","standard","I54";
;
CDS_LIB"standard"
BODY_TYPE"PLUMBING"
HDL_TAP"TRUE";
"B \NAC \NWC"11;
"S \NAC"
BN"0"155;
%"TAP"
"1","(-2175,2750)","2","standard","I55";
;
CDS_LIB"standard"
BODY_TYPE"PLUMBING"
HDL_TAP"TRUE";
"B \NAC \NWC"11;
"S \NAC"
BN"2"156;
%"TAP"
"1","(-2175,2800)","2","standard","I56";
;
CDS_LIB"standard"
BODY_TYPE"PLUMBING"
HDL_TAP"TRUE";
"B \NAC \NWC"11;
"S \NAC"
BN"3"157;
%"TAP"
"1","(-2175,2850)","2","standard","I57";
;
CDS_LIB"standard"
BODY_TYPE"PLUMBING"
HDL_TAP"TRUE";
"B \NAC \NWC"11;
"S \NAC"
BN"4"175;
%"TAP"
"1","(-2175,2950)","2","standard","I58";
;
CDS_LIB"standard"
BODY_TYPE"PLUMBING"
HDL_TAP"TRUE";
"B \NAC \NWC"11;
"S \NAC"
BN"6"159;
%"TAP"
"1","(-2175,2900)","2","standard","I59";
;
CDS_LIB"standard"
BODY_TYPE"PLUMBING"
HDL_TAP"TRUE";
"B \NAC \NWC"11;
"S \NAC"
BN"5"158;
%"TAP"
"1","(-2175,3000)","2","standard","I60";
;
CDS_LIB"standard"
BODY_TYPE"PLUMBING"
HDL_TAP"TRUE";
"B \NAC \NWC"11;
"S \NAC"
BN"7"176;
%"TAP"
"1","(-2175,3700)","2","standard","I61";
;
CDS_LIB"standard"
BODY_TYPE"PLUMBING"
HDL_TAP"TRUE";
"B \NAC \NWC"13;
"S \NAC"
BN"0"172;
%"TAP"
"1","(-2175,3750)","2","standard","I62";
;
CDS_LIB"standard"
BODY_TYPE"PLUMBING"
HDL_TAP"TRUE";
"B \NAC \NWC"13;
"S \NAC"
BN"1"170;
%"TAP"
"1","(-2175,3850)","2","standard","I63";
;
CDS_LIB"standard"
BODY_TYPE"PLUMBING"
HDL_TAP"TRUE";
"B \NAC \NWC"13;
"S \NAC"
BN"3"166;
%"TAP"
"1","(-2175,3800)","2","standard","I64";
;
CDS_LIB"standard"
BODY_TYPE"PLUMBING"
HDL_TAP"TRUE";
"B \NAC \NWC"13;
"S \NAC"
BN"2"168;
%"TAP"
"1","(-2175,3900)","2","standard","I65";
;
CDS_LIB"standard"
BODY_TYPE"PLUMBING"
HDL_TAP"TRUE";
"B \NAC \NWC"13;
"S \NAC"
BN"4"164;
%"TAP"
"1","(-2175,4000)","2","standard","I66";
;
CDS_LIB"standard"
BODY_TYPE"PLUMBING"
HDL_TAP"TRUE";
"B \NAC \NWC"13;
"S \NAC"
BN"6"160;
%"TAP"
"1","(-2175,3950)","2","standard","I67";
;
CDS_LIB"standard"
BODY_TYPE"PLUMBING"
HDL_TAP"TRUE";
"B \NAC \NWC"13;
"S \NAC"
BN"5"162;
%"TAP"
"1","(-2175,4100)","2","standard","I68";
;
CDS_LIB"standard"
BODY_TYPE"PLUMBING"
HDL_TAP"TRUE";
"B \NAC \NWC"12;
"S \NAC"
BN"0"173;
%"TAP"
"1","(-2175,4150)","2","standard","I69";
;
CDS_LIB"standard"
BODY_TYPE"PLUMBING"
HDL_TAP"TRUE";
"B \NAC \NWC"12;
"S \NAC"
BN"1"171;
%"TAP"
"1","(-2175,4200)","2","standard","I70";
;
CDS_LIB"standard"
BODY_TYPE"PLUMBING"
HDL_TAP"TRUE";
"B \NAC \NWC"12;
"S \NAC"
BN"2"169;
%"TAP"
"1","(-2175,4250)","2","standard","I71";
;
CDS_LIB"standard"
BODY_TYPE"PLUMBING"
HDL_TAP"TRUE";
"B \NAC \NWC"12;
"S \NAC"
BN"3"167;
%"TAP"
"1","(-525,2250)","0","standard","I72";
;
CDS_LIB"standard"
BODY_TYPE"PLUMBING"
HDL_TAP"TRUE";
"B \NAC \NWC"15;
"S \NAC"
BN"21"109;
%"TAP"
"1","(-525,2300)","0","standard","I73";
;
CDS_LIB"standard"
BODY_TYPE"PLUMBING"
HDL_TAP"TRUE";
"B \NAC \NWC"15;
"S \NAC"
BN"22"110;
%"TAP"
"1","(-525,2350)","0","standard","I74";
;
CDS_LIB"standard"
BODY_TYPE"PLUMBING"
HDL_TAP"TRUE";
"B \NAC \NWC"15;
"S \NAC"
BN"23"84;
%"TAP"
"1","(-525,2400)","0","standard","I75";
;
CDS_LIB"standard"
BODY_TYPE"PLUMBING"
HDL_TAP"TRUE";
"B \NAC \NWC"15;
"S \NAC"
BN"24"83;
%"TAP"
"1","(-525,2500)","0","standard","I76";
;
CDS_LIB"standard"
BODY_TYPE"PLUMBING"
HDL_TAP"TRUE";
"B \NAC \NWC"15;
"S \NAC"
BN"26"112;
%"TAP"
"1","(-525,2450)","0","standard","I77";
;
CDS_LIB"standard"
BODY_TYPE"PLUMBING"
HDL_TAP"TRUE";
"B \NAC \NWC"15;
"S \NAC"
BN"25"111;
%"TAP"
"1","(-525,2550)","0","standard","I78";
;
CDS_LIB"standard"
BODY_TYPE"PLUMBING"
HDL_TAP"TRUE";
"B \NAC \NWC"15;
"S \NAC"
BN"27"113;
%"TAP"
"1","(-525,2600)","0","standard","I79";
;
CDS_LIB"standard"
BODY_TYPE"PLUMBING"
HDL_TAP"TRUE";
"B \NAC \NWC"15;
"S \NAC"
BN"28"114;
%"TAP"
"1","(-525,2650)","0","standard","I80";
;
CDS_LIB"standard"
BODY_TYPE"PLUMBING"
HDL_TAP"TRUE";
"B \NAC \NWC"15;
"S \NAC"
BN"29"115;
%"TAP"
"1","(-525,2750)","0","standard","I81";
;
CDS_LIB"standard"
BODY_TYPE"PLUMBING"
HDL_TAP"TRUE";
"B \NAC \NWC"15;
"S \NAC"
BN"31"117;
%"TAP"
"1","(-525,2700)","0","standard","I82";
;
CDS_LIB"standard"
BODY_TYPE"PLUMBING"
HDL_TAP"TRUE";
"B \NAC \NWC"15;
"S \NAC"
BN"30"116;
%"TAP"
"1","(-525,2850)","0","standard","I83";
;
CDS_LIB"standard"
BODY_TYPE"PLUMBING"
HDL_TAP"TRUE";
"B \NAC \NWC"10;
"S \NAC"
BN"0"118;
%"TAP"
"1","(-525,2900)","0","standard","I84";
;
CDS_LIB"standard"
BODY_TYPE"PLUMBING"
HDL_TAP"TRUE";
"B \NAC \NWC"10;
"S \NAC"
BN"1"119;
%"TAP"
"1","(-525,2950)","0","standard","I85";
;
CDS_LIB"standard"
BODY_TYPE"PLUMBING"
HDL_TAP"TRUE";
"B \NAC \NWC"10;
"S \NAC"
BN"2"120;
%"TAP"
"1","(-525,3000)","0","standard","I86";
;
CDS_LIB"standard"
BODY_TYPE"PLUMBING"
HDL_TAP"TRUE";
"B \NAC \NWC"10;
"S \NAC"
BN"3"121;
%"TAP"
"1","(-525,3050)","0","standard","I87";
;
CDS_LIB"standard"
BODY_TYPE"PLUMBING"
HDL_TAP"TRUE";
"B \NAC \NWC"10;
"S \NAC"
BN"4"122;
%"TAP"
"1","(-525,3100)","0","standard","I88";
;
CDS_LIB"standard"
BODY_TYPE"PLUMBING"
HDL_TAP"TRUE";
"B \NAC \NWC"10;
"S \NAC"
BN"5"123;
%"TAP"
"1","(-525,3150)","0","standard","I89";
;
CDS_LIB"standard"
BODY_TYPE"PLUMBING"
HDL_TAP"TRUE";
"B \NAC \NWC"10;
"S \NAC"
BN"6"124;
%"TAP"
"1","(-525,3200)","0","standard","I90";
;
CDS_LIB"standard"
BODY_TYPE"PLUMBING"
HDL_TAP"TRUE";
"B \NAC \NWC"10;
"S \NAC"
BN"7"125;
%"TAP"
"1","(-525,3250)","0","standard","I91";
;
CDS_LIB"standard"
BODY_TYPE"PLUMBING"
HDL_TAP"TRUE";
"B \NAC \NWC"10;
"S \NAC"
BN"8"126;
%"TAP"
"1","(-525,3350)","0","standard","I92";
;
CDS_LIB"standard"
BODY_TYPE"PLUMBING"
HDL_TAP"TRUE";
"B \NAC \NWC"10;
"S \NAC"
BN"10"128;
%"TAP"
"1","(-525,3300)","0","standard","I93";
;
CDS_LIB"standard"
BODY_TYPE"PLUMBING"
HDL_TAP"TRUE";
"B \NAC \NWC"10;
"S \NAC"
BN"9"127;
%"TAP"
"1","(-525,3400)","0","standard","I94";
;
CDS_LIB"standard"
BODY_TYPE"PLUMBING"
HDL_TAP"TRUE";
"B \NAC \NWC"10;
"S \NAC"
BN"11"129;
%"TAP"
"1","(-525,3450)","0","standard","I95";
;
CDS_LIB"standard"
BODY_TYPE"PLUMBING"
HDL_TAP"TRUE";
"B \NAC \NWC"10;
"S \NAC"
BN"12"76;
%"TAP"
"1","(-525,3500)","0","standard","I96";
;
CDS_LIB"standard"
BODY_TYPE"PLUMBING"
HDL_TAP"TRUE";
"B \NAC \NWC"10;
"S \NAC"
BN"13"130;
%"TAP"
"1","(-525,3550)","0","standard","I97";
;
CDS_LIB"standard"
BODY_TYPE"PLUMBING"
HDL_TAP"TRUE";
"B \NAC \NWC"10;
"S \NAC"
BN"14"131;
%"TAP"
"1","(-525,3650)","0","standard","I98";
;
CDS_LIB"standard"
BODY_TYPE"PLUMBING"
HDL_TAP"TRUE";
"B \NAC \NWC"10;
"S \NAC"
BN"16"133;
%"TAP"
"1","(-525,3600)","0","standard","I99";
;
CDS_LIB"standard"
BODY_TYPE"PLUMBING"
HDL_TAP"TRUE";
"B \NAC \NWC"10;
"S \NAC"
BN"15"132;
END.
